(kicad_pcb
	(version 20260206)
	(generator "pcbnew")
	(generator_version "10.0")
	(general
		(thickness 1.6)
		(legacy_teardrops no)
	)
	(paper "A4")
	(title_block
		(title "Wiwynn_Tioga_Pass_MB.brd")
		(comment 1 "Tioga Pass / footprint 1366 of 4770 (J6B1), pads 1-122 of 122")
	)
	(layers
		(0 "F.Cu" signal "TOP")
		(4 "In1.Cu" signal "L2GND")
		(6 "In2.Cu" signal "L3")
		(8 "In3.Cu" signal "L4GND")
		(10 "In4.Cu" signal "L5")
		(12 "In5.Cu" signal "L6GND")
		(14 "In6.Cu" signal "L7VCC")
		(16 "In7.Cu" signal "L8VCC")
		(18 "In8.Cu" signal "L9GND")
		(20 "In9.Cu" signal "L10")
		(22 "In10.Cu" signal "L11GND")
		(24 "In11.Cu" signal "L12")
		(26 "In12.Cu" signal "L13GND")
		(2 "B.Cu" signal "BOTTOM")
		(9 "F.Adhes" user "F.Adhesive")
		(11 "B.Adhes" user "B.Adhesive")
		(13 "F.Paste" user "Package Geometry/Pastemask Top")
		(15 "B.Paste" user "Package Geometry/Pastemask Bottom")
		(5 "F.SilkS" user "Ref Des/Silkscreen Top")
		(7 "B.SilkS" user "Ref Des/Silkscreen Bottom")
		(1 "F.Mask" user "Board Geometry/Soldermask Top")
		(3 "B.Mask" user "Board Geometry/Soldermask Bottom")
		(17 "Dwgs.User" user "User.Drawings")
		(19 "Cmts.User" user "User.Comments")
		(21 "Eco1.User" user "User.Eco1")
		(23 "Eco2.User" user "User.Eco2")
		(25 "Edge.Cuts" user "Board Geometry/Outline")
		(27 "Margin" user)
		(31 "F.CrtYd" user "Package Geometry/Place Bound Top")
		(29 "B.CrtYd" user "Package Geometry/Place Bound Bottom")
		(35 "F.Fab" user "Ref Des/Assembly Top")
		(33 "B.Fab" user "Ref Des/Assembly Bottom")
	)
	(footprint ""
		(layer "F.Cu")
		(at 329.594972 -115.55095 90)
		(property "Reference" "J6B1"
			(at -3.59283 -5.018024 90)
			(unlocked yes)
			(layer "F.SilkS")
			(effects
				(font
					(size 0.7874 0.5842)
					(thickness 0.1524)
				)
			)
		)
		(property "Value" ""
			(at 0 0 90)
			(layer "F.Fab")
			(effects
				(font
					(size 1.27 1.27)
				)
			)
		)
		(duplicate_pad_numbers_are_jumpers no)
		(pad "" np_thru_hole circle
			(at -3.175 26.5557 90)
			(size 0.254 0.254)
			(drill 1.27)
			(layers "*.Cu" "*.Mask")
			(clearance 0.8255)
			(thermal_gap 0.8255)
		)
		(pad "" np_thru_hole circle
			(at -0.127 -2.4257 90)
			(size 0.254 0.254)
			(drill 1.27)
			(layers "*.Cu" "*.Mask")
			(clearance 0.8255)
			(thermal_gap 0.8255)
		)
		(pad "A1" smd circle
			(at 0 0 90)
			(size 0.635 0.635)
			(layers "F.Cu" "F.Mask" "F.Paste")
			(net "P12V_STBY")
		)
		(pad "A2" smd circle
			(at 0 1.27 90)
			(size 0.635 0.635)
			(layers "F.Cu" "F.Mask" "F.Paste")
			(net "P12V_STBY")
		)
		(pad "A3" smd circle
			(at 0 2.54 90)
			(size 0.635 0.635)
			(layers "F.Cu" "F.Mask" "F.Paste")
			(net "P12V_STBY")
		)
		(pad "A4" smd circle
			(at 0 3.81 90)
			(size 0.635 0.635)
			(layers "F.Cu" "F.Mask" "F.Paste")
			(net "P12V_STBY")
		)
		(pad "A5" smd circle
			(at 0 5.08 90)
			(size 0.635 0.635)
			(layers "F.Cu" "F.Mask" "F.Paste")
			(net "P12V_STBY")
		)
		(pad "A6" smd circle
			(at 0 6.35 90)
			(size 0.635 0.635)
			(layers "F.Cu" "F.Mask" "F.Paste")
			(net "P12V_STBY")
		)
		(pad "A7" smd circle
			(at 0 7.62 90)
			(size 0.635 0.635)
			(layers "F.Cu" "F.Mask" "F.Paste")
			(net "P12V_STBY")
		)
		(pad "A8" smd circle
			(at 0 8.89 90)
			(size 0.635 0.635)
			(layers "F.Cu" "F.Mask" "F.Paste")
			(net "P12V_STBY")
		)
		(pad "A9" smd circle
			(at 0 10.16 90)
			(size 0.635 0.635)
			(layers "F.Cu" "F.Mask" "F.Paste")
			(net "GND")
		)
		(pad "A10" smd circle
			(at 0 11.43 90)
			(size 0.635 0.635)
			(layers "F.Cu" "F.Mask" "F.Paste")
			(net "GND")
		)
		(pad "A11" smd circle
			(at 0 12.7 90)
			(size 0.635 0.635)
			(layers "F.Cu" "F.Mask" "F.Paste")
			(net "P3V3_STBY")
		)
		(pad "A12" smd circle
			(at 0 13.97 90)
			(size 0.635 0.635)
			(layers "F.Cu" "F.Mask" "F.Paste")
			(net "GND")
		)
		(pad "A13" smd circle
			(at 0 15.24 90)
			(size 0.635 0.635)
			(layers "F.Cu" "F.Mask" "F.Paste")
			(net "P5V_STBY")
		)
		(pad "A14" smd circle
			(at 0 16.51 90)
			(size 0.635 0.635)
			(layers "F.Cu" "F.Mask" "F.Paste")
			(net "GND")
		)
		(pad "A15" smd circle
			(at 0 17.78 90)
			(size 0.635 0.635)
			(layers "F.Cu" "F.Mask" "F.Paste")
			(net "FM_P1V8MCP_CPU0_EN")
		)
		(pad "A16" smd circle
			(at 0 19.05 90)
			(size 0.635 0.635)
			(layers "F.Cu" "F.Mask" "F.Paste")
			(net "FM_PVCCIOMCP_CPU0_EN")
		)
		(pad "A17" smd circle
			(at 0 20.32 90)
			(size 0.635 0.635)
			(layers "F.Cu" "F.Mask" "F.Paste")
			(net "GND")
		)
		(pad "A18" smd circle
			(at 0 21.59 90)
			(size 0.635 0.635)
			(layers "F.Cu" "F.Mask" "F.Paste")
			(net "SMB_VR_STBY_LVC3_SCL")
		)
		(pad "A19" smd circle
			(at 0 22.86 90)
			(size 0.635 0.635)
			(layers "F.Cu" "F.Mask" "F.Paste")
			(net "SVID_ALERT0_CPU0_R_N")
		)
		(pad "A20" smd circle
			(at 0 24.13 90)
			(size 0.635 0.635)
			(layers "F.Cu" "F.Mask" "F.Paste")
			(net "SVID_CLK0_CPU0_R")
		)
		(pad "B1" smd circle
			(at -1.27 0 90)
			(size 0.635 0.635)
			(layers "F.Cu" "F.Mask" "F.Paste")
			(net "P12V_STBY")
		)
		(pad "B2" smd circle
			(at -1.27 1.27 90)
			(size 0.635 0.635)
			(layers "F.Cu" "F.Mask" "F.Paste")
			(net "P12V_STBY")
		)
		(pad "B3" smd circle
			(at -1.27 2.54 90)
			(size 0.635 0.635)
			(layers "F.Cu" "F.Mask" "F.Paste")
			(net "P12V_STBY")
		)
		(pad "B4" smd circle
			(at -1.27 3.81 90)
			(size 0.635 0.635)
			(layers "F.Cu" "F.Mask" "F.Paste")
			(net "P12V_STBY")
		)
		(pad "B5" smd circle
			(at -1.27 5.08 90)
			(size 0.635 0.635)
			(layers "F.Cu" "F.Mask" "F.Paste")
			(net "P12V_STBY")
		)
		(pad "B6" smd circle
			(at -1.27 6.35 90)
			(size 0.635 0.635)
			(layers "F.Cu" "F.Mask" "F.Paste")
			(net "P12V_STBY")
		)
		(pad "B7" smd circle
			(at -1.27 7.62 90)
			(size 0.635 0.635)
			(layers "F.Cu" "F.Mask" "F.Paste")
			(net "P12V_STBY")
		)
		(pad "B8" smd circle
			(at -1.27 8.89 90)
			(size 0.635 0.635)
			(layers "F.Cu" "F.Mask" "F.Paste")
			(net "P12V_STBY")
		)
		(pad "B9" smd circle
			(at -1.27 10.16 90)
			(size 0.635 0.635)
			(layers "F.Cu" "F.Mask" "F.Paste")
			(net "GND")
		)
		(pad "B10" smd circle
			(at -1.27 11.43 90)
			(size 0.635 0.635)
			(layers "F.Cu" "F.Mask" "F.Paste")
			(net "GND")
		)
		(pad "B11" smd circle
			(at -1.27 12.7 90)
			(size 0.635 0.635)
			(layers "F.Cu" "F.Mask" "F.Paste")
			(net "P3V3_STBY")
		)
		(pad "B12" smd circle
			(at -1.27 13.97 90)
			(size 0.635 0.635)
			(layers "F.Cu" "F.Mask" "F.Paste")
			(net "GND")
		)
		(pad "B13" smd circle
			(at -1.27 15.24 90)
			(size 0.635 0.635)
			(layers "F.Cu" "F.Mask" "F.Paste")
			(net "P5V_STBY")
		)
		(pad "B14" smd circle
			(at -1.27 16.51 90)
			(size 0.635 0.635)
			(layers "F.Cu" "F.Mask" "F.Paste")
			(net "GND")
		)
		(pad "B15" smd circle
			(at -1.27 17.78 90)
			(size 0.635 0.635)
			(layers "F.Cu" "F.Mask" "F.Paste")
			(net "PWRGD_P1V8MCP_CPU0")
		)
		(pad "B16" smd circle
			(at -1.27 19.05 90)
			(size 0.635 0.635)
			(layers "F.Cu" "F.Mask" "F.Paste")
			(net "PWRGD_PVCCIOMCP_CPU0")
		)
		(pad "B17" smd circle
			(at -1.27 20.32 90)
			(size 0.635 0.635)
			(layers "F.Cu" "F.Mask" "F.Paste")
			(net "GND")
		)
		(pad "B18" smd circle
			(at -1.27 21.59 90)
			(size 0.635 0.635)
			(layers "F.Cu" "F.Mask" "F.Paste")
			(net "SMB_VR_STBY_LVC3_SDA")
		)
		(pad "B19" smd circle
			(at -1.27 22.86 90)
			(size 0.635 0.635)
			(layers "F.Cu" "F.Mask" "F.Paste")
			(net "SVID_ALERT1_CPU0_R_N")
		)
		(pad "B20" smd circle
			(at -1.27 24.13 90)
			(size 0.635 0.635)
			(layers "F.Cu" "F.Mask" "F.Paste")
			(net "SVID_DIO0_CPU0_R")
		)
		(pad "C1" smd circle
			(at -2.54 0 90)
			(size 0.635 0.635)
			(layers "F.Cu" "F.Mask" "F.Paste")
			(net "GND")
		)
		(pad "C2" smd circle
			(at -2.54 1.27 90)
			(size 0.635 0.635)
			(layers "F.Cu" "F.Mask" "F.Paste")
			(net "GND")
		)
		(pad "C3" smd circle
			(at -2.54 2.54 90)
			(size 0.635 0.635)
			(layers "F.Cu" "F.Mask" "F.Paste")
			(net "GND")
		)
		(pad "C4" smd circle
			(at -2.54 3.81 90)
			(size 0.635 0.635)
			(layers "F.Cu" "F.Mask" "F.Paste")
			(net "GND")
		)
		(pad "C5" smd circle
			(at -2.54 5.08 90)
			(size 0.635 0.635)
			(layers "F.Cu" "F.Mask" "F.Paste")
			(net "GND")
		)
		(pad "C6" smd circle
			(at -2.54 6.35 90)
			(size 0.635 0.635)
			(layers "F.Cu" "F.Mask" "F.Paste")
			(net "GND")
		)
		(pad "C7" smd circle
			(at -2.54 7.62 90)
			(size 0.635 0.635)
			(layers "F.Cu" "F.Mask" "F.Paste")
			(net "GND")
		)
		(pad "C8" smd circle
			(at -2.54 8.89 90)
			(size 0.635 0.635)
			(layers "F.Cu" "F.Mask" "F.Paste")
			(net "GND")
		)
		(pad "C9" smd circle
			(at -2.54 10.16 90)
			(size 0.635 0.635)
			(layers "F.Cu" "F.Mask" "F.Paste")
			(net "GND")
		)
		(pad "C10" smd circle
			(at -2.54 11.43 90)
			(size 0.635 0.635)
			(layers "F.Cu" "F.Mask" "F.Paste")
			(net "GND")
		)
		(pad "C11" smd circle
			(at -2.54 12.7 90)
			(size 0.635 0.635)
			(layers "F.Cu" "F.Mask" "F.Paste")
			(net "P3V3_STBY")
		)
		(pad "C12" smd circle
			(at -2.54 13.97 90)
			(size 0.635 0.635)
			(layers "F.Cu" "F.Mask" "F.Paste")
			(net "GND")
		)
		(pad "C13" smd circle
			(at -2.54 15.24 90)
			(size 0.635 0.635)
			(layers "F.Cu" "F.Mask" "F.Paste")
			(net "P5V_STBY")
		)
		(pad "C14" smd circle
			(at -2.54 16.51 90)
			(size 0.635 0.635)
			(layers "F.Cu" "F.Mask" "F.Paste")
			(net "GND")
		)
		(pad "C15" smd circle
			(at -2.54 17.78 90)
			(size 0.635 0.635)
			(layers "F.Cu" "F.Mask" "F.Paste")
			(net "GND")
		)
		(pad "C16" smd circle
			(at -2.54 19.05 90)
			(size 0.635 0.635)
			(layers "F.Cu" "F.Mask" "F.Paste")
			(net "GND")
		)
		(pad "C17" smd circle
			(at -2.54 20.32 90)
			(size 0.635 0.635)
			(layers "F.Cu" "F.Mask" "F.Paste")
			(net "PVCCIOMCP_CPU0")
		)
		(pad "C18" smd circle
			(at -2.54 21.59 90)
			(size 0.635 0.635)
			(layers "F.Cu" "F.Mask" "F.Paste")
			(net "PVCCIOMCP_CPU0")
		)
		(pad "C19" smd circle
			(at -2.54 22.86 90)
			(size 0.635 0.635)
			(layers "F.Cu" "F.Mask" "F.Paste")
			(net "PVCCIOMCP_CPU0")
		)
		(pad "C20" smd circle
			(at -2.54 24.13 90)
			(size 0.635 0.635)
			(layers "F.Cu" "F.Mask" "F.Paste")
			(net "FM_PVCCMCP_CPU0_EN")
		)
		(pad "D1" smd circle
			(at -3.81 0 90)
			(size 0.635 0.635)
			(layers "F.Cu" "F.Mask" "F.Paste")
			(net "P3V3")
		)
		(pad "D2" smd circle
			(at -3.81 1.27 90)
			(size 0.635 0.635)
			(layers "F.Cu" "F.Mask" "F.Paste")
			(net "GND")
		)
		(pad "D3" smd circle
			(at -3.81 2.54 90)
			(size 0.635 0.635)
			(layers "F.Cu" "F.Mask" "F.Paste")
			(net "GND")
		)
		(pad "D4" smd circle
			(at -3.81 3.81 90)
			(size 0.635 0.635)
			(layers "F.Cu" "F.Mask" "F.Paste")
			(net "GND")
		)
		(pad "D5" smd circle
			(at -3.81 5.08 90)
			(size 0.635 0.635)
			(layers "F.Cu" "F.Mask" "F.Paste")
			(net "GND")
		)
		(pad "D6" smd circle
			(at -3.81 6.35 90)
			(size 0.635 0.635)
			(layers "F.Cu" "F.Mask" "F.Paste")
			(net "GND")
		)
		(pad "D7" smd circle
			(at -3.81 7.62 90)
			(size 0.635 0.635)
			(layers "F.Cu" "F.Mask" "F.Paste")
			(net "GND")
		)
		(pad "D8" smd circle
			(at -3.81 8.89 90)
			(size 0.635 0.635)
			(layers "F.Cu" "F.Mask" "F.Paste")
			(net "GND")
		)
		(pad "D9" smd circle
			(at -3.81 10.16 90)
			(size 0.635 0.635)
			(layers "F.Cu" "F.Mask" "F.Paste")
			(net "GND")
		)
		(pad "D10" smd circle
			(at -3.81 11.43 90)
			(size 0.635 0.635)
			(layers "F.Cu" "F.Mask" "F.Paste")
			(net "GND")
		)
		(pad "D11" smd circle
			(at -3.81 12.7 90)
			(size 0.635 0.635)
			(layers "F.Cu" "F.Mask" "F.Paste")
			(net "GND")
		)
		(pad "D12" smd circle
			(at -3.81 13.97 90)
			(size 0.635 0.635)
			(layers "F.Cu" "F.Mask" "F.Paste")
			(net "GND")
		)
		(pad "D13" smd circle
			(at -3.81 15.24 90)
			(size 0.635 0.635)
			(layers "F.Cu" "F.Mask" "F.Paste")
			(net "GND")
		)
		(pad "D14" smd circle
			(at -3.81 16.51 90)
			(size 0.635 0.635)
			(layers "F.Cu" "F.Mask" "F.Paste")
			(net "GND")
		)
		(pad "D15" smd circle
			(at -3.81 17.78 90)
			(size 0.635 0.635)
			(layers "F.Cu" "F.Mask" "F.Paste")
			(net "GND")
		)
		(pad "D16" smd circle
			(at -3.81 19.05 90)
			(size 0.635 0.635)
			(layers "F.Cu" "F.Mask" "F.Paste")
			(net "GND")
		)
		(pad "D17" smd circle
			(at -3.81 20.32 90)
			(size 0.635 0.635)
			(layers "F.Cu" "F.Mask" "F.Paste")
			(net "PVCCIOMCP_CPU0")
		)
		(pad "D18" smd circle
			(at -3.81 21.59 90)
			(size 0.635 0.635)
			(layers "F.Cu" "F.Mask" "F.Paste")
			(net "PVCCIOMCP_CPU0")
		)
		(pad "D19" smd circle
			(at -3.81 22.86 90)
			(size 0.635 0.635)
			(layers "F.Cu" "F.Mask" "F.Paste")
			(net "PVCCIOMCP_CPU0")
		)
		(pad "D20" smd circle
			(at -3.81 24.13 90)
			(size 0.635 0.635)
			(layers "F.Cu" "F.Mask" "F.Paste")
			(net "PWRGD_PVCCMCP_CPU0")
		)
		(pad "E1" smd circle
			(at -5.08 0 90)
			(size 0.635 0.635)
			(layers "F.Cu" "F.Mask" "F.Paste")
			(net "FM_CPU0_VRM_322M_156M_OSC_EN")
		)
		(pad "E2" smd circle
			(at -5.08 1.27 90)
			(size 0.635 0.635)
			(layers "F.Cu" "F.Mask" "F.Paste")
			(net "GND")
		)
		(pad "E3" smd circle
			(at -5.08 2.54 90)
			(size 0.635 0.635)
			(layers "F.Cu" "F.Mask" "F.Paste")
			(net "GND")
		)
		(pad "E4" smd circle
			(at -5.08 3.81 90)
			(size 0.635 0.635)
			(layers "F.Cu" "F.Mask" "F.Paste")
			(net "GND")
		)
		(pad "E5" smd circle
			(at -5.08 5.08 90)
			(size 0.635 0.635)
			(layers "F.Cu" "F.Mask" "F.Paste")
			(net "GND")
		)
		(pad "E6" smd circle
			(at -5.08 6.35 90)
			(size 0.635 0.635)
			(layers "F.Cu" "F.Mask" "F.Paste")
			(net "GND")
		)
		(pad "E7" smd circle
			(at -5.08 7.62 90)
			(size 0.635 0.635)
			(layers "F.Cu" "F.Mask" "F.Paste")
			(net "GND")
		)
		(pad "E8" smd circle
			(at -5.08 8.89 90)
			(size 0.635 0.635)
			(layers "F.Cu" "F.Mask" "F.Paste")
			(net "VSENSE_PVCCIOMCP_CPU0_SKT_VSEN")
		)
		(pad "E9" smd circle
			(at -5.08 10.16 90)
			(size 0.635 0.635)
			(layers "F.Cu" "F.Mask" "F.Paste")
			(net "GND")
		)
		(pad "E10" smd circle
			(at -5.08 11.43 90)
			(size 0.635 0.635)
			(layers "F.Cu" "F.Mask" "F.Paste")
			(net "VR_PVCCIOMCP_CPU0_XADDR1")
		)
		(pad "E11" smd circle
			(at -5.08 12.7 90)
			(size 0.635 0.635)
			(layers "F.Cu" "F.Mask" "F.Paste")
			(net "GND")
		)
		(pad "E12" smd circle
			(at -5.08 13.97 90)
			(size 0.635 0.635)
			(layers "F.Cu" "F.Mask" "F.Paste")
			(net "GND")
		)
		(pad "E13" smd circle
			(at -5.08 15.24 90)
			(size 0.635 0.635)
			(layers "F.Cu" "F.Mask" "F.Paste")
			(net "GND")
		)
		(pad "E14" smd circle
			(at -5.08 16.51 90)
			(size 0.635 0.635)
			(layers "F.Cu" "F.Mask" "F.Paste")
			(net "GND")
		)
		(pad "E15" smd circle
			(at -5.08 17.78 90)
			(size 0.635 0.635)
			(layers "F.Cu" "F.Mask" "F.Paste")
			(net "PVCCIOMCP_CPU0")
		)
		(pad "E16" smd circle
			(at -5.08 19.05 90)
			(size 0.635 0.635)
			(layers "F.Cu" "F.Mask" "F.Paste")
			(net "PVCCIOMCP_CPU0")
		)
		(pad "E17" smd circle
			(at -5.08 20.32 90)
			(size 0.635 0.635)
			(layers "F.Cu" "F.Mask" "F.Paste")
			(net "PVCCIOMCP_CPU0")
		)
		(pad "E18" smd circle
			(at -5.08 21.59 90)
			(size 0.635 0.635)
			(layers "F.Cu" "F.Mask" "F.Paste")
			(net "PVCCIOMCP_CPU0")
		)
		(pad "E19" smd circle
			(at -5.08 22.86 90)
			(size 0.635 0.635)
			(layers "F.Cu" "F.Mask" "F.Paste")
			(net "PVCCIOMCP_CPU0")
		)
		(pad "E20" smd circle
			(at -5.08 24.13 90)
			(size 0.635 0.635)
			(layers "F.Cu" "F.Mask" "F.Paste")
			(net "SVID_CLK1_CPU0_R")
		)
		(pad "F1" smd circle
			(at -6.35 0 90)
			(size 0.635 0.635)
			(layers "F.Cu" "F.Mask" "F.Paste")
			(net "PVCCIO_CPU0")
		)
		(pad "F2" smd circle
			(at -6.35 1.27 90)
			(size 0.635 0.635)
			(layers "F.Cu" "F.Mask" "F.Paste")
			(net "GND")
		)
		(pad "F3" smd circle
			(at -6.35 2.54 90)
			(size 0.635 0.635)
			(layers "F.Cu" "F.Mask" "F.Paste")
			(net "GND")
		)
		(pad "F4" smd circle
			(at -6.35 3.81 90)
			(size 0.635 0.635)
			(layers "F.Cu" "F.Mask" "F.Paste")
			(net "GND")
		)
		(pad "F5" smd circle
			(at -6.35 5.08 90)
			(size 0.635 0.635)
			(layers "F.Cu" "F.Mask" "F.Paste")
			(net "GND")
		)
		(pad "F6" smd circle
			(at -6.35 6.35 90)
			(size 0.635 0.635)
			(layers "F.Cu" "F.Mask" "F.Paste")
			(net "GND")
		)
		(pad "F7" smd circle
			(at -6.35 7.62 90)
			(size 0.635 0.635)
			(layers "F.Cu" "F.Mask" "F.Paste")
			(net "GND")
		)
		(pad "F8" smd circle
			(at -6.35 8.89 90)
			(size 0.635 0.635)
			(layers "F.Cu" "F.Mask" "F.Paste")
			(net "VSENSE_PVCCIOMCP_CPU0_SKT_VRTN")
		)
		(pad "F9" smd circle
			(at -6.35 10.16 90)
			(size 0.635 0.635)
			(layers "F.Cu" "F.Mask" "F.Paste")
			(net "GND")
		)
		(pad "F10" smd circle
			(at -6.35 11.43 90)
			(size 0.635 0.635)
			(layers "F.Cu" "F.Mask" "F.Paste")
			(net "VR_PVCCMCP_CPU0_XADDR2")
		)
		(pad "F11" smd circle
			(at -6.35 12.7 90)
			(size 0.635 0.635)
			(layers "F.Cu" "F.Mask" "F.Paste")
			(net "GND")
		)
		(pad "F12" smd circle
			(at -6.35 13.97 90)
			(size 0.635 0.635)
			(layers "F.Cu" "F.Mask" "F.Paste")
			(net "GND")
		)
		(pad "F13" smd circle
			(at -6.35 15.24 90)
			(size 0.635 0.635)
			(layers "F.Cu" "F.Mask" "F.Paste")
			(net "GND")
		)
		(pad "F14" smd circle
			(at -6.35 16.51 90)
			(size 0.635 0.635)
			(layers "F.Cu" "F.Mask" "F.Paste")
			(net "GND")
		)
		(pad "F15" smd circle
			(at -6.35 17.78 90)
			(size 0.635 0.635)
			(layers "F.Cu" "F.Mask" "F.Paste")
			(net "PVCCIOMCP_CPU0")
		)
		(pad "F16" smd circle
			(at -6.35 19.05 90)
			(size 0.635 0.635)
			(layers "F.Cu" "F.Mask" "F.Paste")
			(net "PVCCIOMCP_CPU0")
		)
		(pad "F17" smd circle
			(at -6.35 20.32 90)
			(size 0.635 0.635)
			(layers "F.Cu" "F.Mask" "F.Paste")
			(net "PVCCIOMCP_CPU0")
		)
		(pad "F18" smd circle
			(at -6.35 21.59 90)
			(size 0.635 0.635)
			(layers "F.Cu" "F.Mask" "F.Paste")
			(net "PVCCIOMCP_CPU0")
		)
		(pad "F19" smd circle
			(at -6.35 22.86 90)
			(size 0.635 0.635)
			(layers "F.Cu" "F.Mask" "F.Paste")
			(net "PVCCIOMCP_CPU0")
		)
		(pad "F20" smd circle
			(at -6.35 24.13 90)
			(size 0.635 0.635)
			(layers "F.Cu" "F.Mask" "F.Paste")
			(net "SVID_DIO1_CPU0_R")
		)
	)
)
